(kicad_pcb
	(version 20260206)
	(generator "pcbnew")
	(generator_version "10.0")
	(general
		(thickness 1.6)
		(legacy_teardrops no)
	)
	(paper "A4")
	(title_block
		(title "01162023_DA0F0TEBIF0_F0T_Expander_BD_F_brd_V02_OCP.brd")
		(comment 1 "Grand Teton / footprints 1550-1556 of 9728")
	)
	(layers
		(0 "F.Cu" signal "TOP")
		(4 "In1.Cu" signal "GND")
		(6 "In2.Cu" signal "VCC")
		(8 "In3.Cu" signal "VCC1")
		(10 "In4.Cu" signal "GND1")
		(12 "In5.Cu" signal "IN1")
		(14 "In6.Cu" signal "GND2")
		(16 "In7.Cu" signal "IN2")
		(18 "In8.Cu" signal "GND3")
		(20 "In9.Cu" signal "IN3")
		(22 "In10.Cu" signal "GND4")
		(24 "In11.Cu" signal "IN4")
		(26 "In12.Cu" signal "GND5")
		(28 "In13.Cu" signal "IN5")
		(30 "In14.Cu" signal "GND6")
		(32 "In15.Cu" signal "IN6")
		(34 "In16.Cu" signal "GND7")
		(2 "B.Cu" signal "BOTTOM")
		(9 "F.Adhes" user "F.Adhesive")
		(11 "B.Adhes" user "B.Adhesive")
		(13 "F.Paste" user "Package Geometry/Pastemask Top")
		(15 "B.Paste" user "Package Geometry/Pastemask Bottom")
		(5 "F.SilkS" user "Ref Des/Silkscreen Top")
		(7 "B.SilkS" user "Ref Des/Silkscreen Bottom")
		(1 "F.Mask" user "Board Geometry/Soldermask Top")
		(3 "B.Mask" user "Board Geometry/Soldermask Bottom")
		(17 "Dwgs.User" user "User.Drawings")
		(19 "Cmts.User" user "User.Comments")
		(21 "Eco1.User" user "User.Eco1")
		(23 "Eco2.User" user "User.Eco2")
		(25 "Edge.Cuts" user "Board Geometry/Outline")
		(27 "Margin" user)
		(31 "F.CrtYd" user "Package Geometry/Place Bound Top")
		(29 "B.CrtYd" user "Package Geometry/Place Bound Bottom")
		(35 "F.Fab" user "Ref Des/Assembly Top")
		(33 "B.Fab" user "Ref Des/Assembly Bottom")
	)
	(footprint ""
		(layer "F.Cu")
		(at 383.66954 -260.088634 -90)
		(property "Reference" "R4591"
			(at 0 0 270)
			(layer "F.SilkS")
			(hide yes)
			(effects
				(font
					(size 1.27 1.27)
				)
			)
		)
		(property "Value" ""
			(at 0 0 270)
			(layer "F.Fab")
			(effects
				(font
					(size 1.27 1.27)
				)
			)
		)
		(duplicate_pad_numbers_are_jumpers no)
		(fp_line
			(start -0.7874 0.4064)
			(end -0.7874 -0.4064)
			(stroke
				(width 0.1524)
				(type default)
			)
			(layer "F.SilkS")
		)
		(fp_line
			(start 0.7874 0.4064)
			(end -0.7874 0.4064)
			(stroke
				(width 0.1524)
				(type default)
			)
			(layer "F.SilkS")
		)
		(fp_line
			(start -0.7874 -0.4064)
			(end 0.7874 -0.4064)
			(stroke
				(width 0.1524)
				(type default)
			)
			(layer "F.SilkS")
		)
		(fp_line
			(start 0.7874 -0.4064)
			(end 0.7874 0.4064)
			(stroke
				(width 0.1524)
				(type default)
			)
			(layer "F.SilkS")
		)
		(fp_line
			(start -0.67945 0.3048)
			(end -0.67945 -0.305054)
			(stroke
				(width 0.1)
				(type default)
			)
			(layer "F.Fab")
		)
		(fp_line
			(start -0.12065 0.3048)
			(end -0.67945 0.3048)
			(stroke
				(width 0.1)
				(type default)
			)
			(layer "F.Fab")
		)
		(fp_line
			(start 0.120396 0.3048)
			(end 0.120396 0.2794)
			(stroke
				(width 0.1)
				(type default)
			)
			(layer "F.Fab")
		)
		(fp_line
			(start 0.67945 0.3048)
			(end 0.120396 0.3048)
			(stroke
				(width 0.1)
				(type default)
			)
			(layer "F.Fab")
		)
		(fp_line
			(start -0.12065 0.2794)
			(end -0.12065 0.3048)
			(stroke
				(width 0.1)
				(type default)
			)
			(layer "F.Fab")
		)
		(fp_line
			(start 0.120396 0.2794)
			(end -0.12065 0.2794)
			(stroke
				(width 0.1)
				(type default)
			)
			(layer "F.Fab")
		)
		(fp_line
			(start -0.12065 -0.2794)
			(end 0.12065 -0.2794)
			(stroke
				(width 0.1)
				(type default)
			)
			(layer "F.Fab")
		)
		(fp_line
			(start 0.12065 -0.2794)
			(end 0.12065 -0.3048)
			(stroke
				(width 0.1)
				(type default)
			)
			(layer "F.Fab")
		)
		(fp_line
			(start 0.12065 -0.3048)
			(end 0.67945 -0.3048)
			(stroke
				(width 0.1)
				(type default)
			)
			(layer "F.Fab")
		)
		(fp_line
			(start 0.67945 -0.3048)
			(end 0.67945 0.3048)
			(stroke
				(width 0.1)
				(type default)
			)
			(layer "F.Fab")
		)
		(fp_line
			(start -0.67945 -0.305054)
			(end -0.12065 -0.305054)
			(stroke
				(width 0.1)
				(type default)
			)
			(layer "F.Fab")
		)
		(fp_line
			(start -0.12065 -0.305054)
			(end -0.12065 -0.2794)
			(stroke
				(width 0.1)
				(type default)
			)
			(layer "F.Fab")
		)
		(pad "1" smd circle
			(at -0.40005 0 270)
			(size 0 0)
			(layers "F.Cu" "F.Mask" "F.Paste")
			(net "PCEPLL3_VDDA18_PEX3")
		)
		(pad "2" smd circle
			(at 0.40005 0 270)
			(size 0 0)
			(layers "F.Cu" "F.Mask" "F.Paste")
			(net "PCEPLL3_VDDA18_PEX3_R")
		)
	)
	(footprint ""
		(layer "F.Cu")
		(at 289.850068 -50.96383 180)
		(property "Reference" "PC573"
			(at 0 0 180)
			(layer "F.SilkS")
			(hide yes)
			(effects
				(font
					(size 1.27 1.27)
				)
			)
		)
		(property "Value" ""
			(at 0 0 180)
			(layer "F.Fab")
			(effects
				(font
					(size 1.27 1.27)
				)
			)
		)
		(duplicate_pad_numbers_are_jumpers no)
		(fp_line
			(start 1.524 0.762)
			(end -1.524 0.762)
			(stroke
				(width 0.1524)
				(type default)
			)
			(layer "F.SilkS")
		)
		(fp_line
			(start 1.524 -0.762)
			(end 1.524 0.762)
			(stroke
				(width 0.1524)
				(type default)
			)
			(layer "F.SilkS")
		)
		(fp_line
			(start -1.524 0.762)
			(end -1.524 -0.762)
			(stroke
				(width 0.1524)
				(type default)
			)
			(layer "F.SilkS")
		)
		(fp_line
			(start -1.524 -0.762)
			(end 1.524 -0.762)
			(stroke
				(width 0.1524)
				(type default)
			)
			(layer "F.SilkS")
		)
		(fp_line
			(start 1.1049 0.724916)
			(end 1.1049 -0.724916)
			(stroke
				(width 0.1)
				(type default)
			)
			(layer "F.Fab")
		)
		(fp_line
			(start 1.1049 -0.724916)
			(end -1.1049 -0.724916)
			(stroke
				(width 0.1)
				(type default)
			)
			(layer "F.Fab")
		)
		(fp_line
			(start -1.1049 0.724916)
			(end 1.1049 0.724916)
			(stroke
				(width 0.1)
				(type default)
			)
			(layer "F.Fab")
		)
		(fp_line
			(start -1.1049 -0.724916)
			(end -1.1049 0.724916)
			(stroke
				(width 0.1)
				(type default)
			)
			(layer "F.Fab")
		)
		(pad "1" smd rect
			(at -0.889 0)
			(size 1.016 1.27)
			(layers "F.Cu" "F.Mask" "F.Paste")
			(net "P3V3_SSD10")
		)
		(pad "2" smd rect
			(at 0.889 0)
			(size 1.016 1.27)
			(layers "F.Cu" "F.Mask" "F.Paste")
			(net "GND")
		)
	)
	(footprint ""
		(layer "F.Cu")
		(at 270.807942 -155.3464 180)
		(property "Reference" "R218"
			(at 0 0 180)
			(layer "F.SilkS")
			(hide yes)
			(effects
				(font
					(size 1.27 1.27)
				)
			)
		)
		(property "Value" ""
			(at 0 0 180)
			(layer "F.Fab")
			(effects
				(font
					(size 1.27 1.27)
				)
			)
		)
		(duplicate_pad_numbers_are_jumpers no)
		(fp_line
			(start 0.7874 0.4064)
			(end -0.7874 0.4064)
			(stroke
				(width 0.1524)
				(type default)
			)
			(layer "F.SilkS")
		)
		(fp_line
			(start 0.7874 -0.4064)
			(end 0.7874 0.4064)
			(stroke
				(width 0.1524)
				(type default)
			)
			(layer "F.SilkS")
		)
		(fp_line
			(start -0.7874 0.4064)
			(end -0.7874 -0.4064)
			(stroke
				(width 0.1524)
				(type default)
			)
			(layer "F.SilkS")
		)
		(fp_line
			(start -0.7874 -0.4064)
			(end 0.7874 -0.4064)
			(stroke
				(width 0.1524)
				(type default)
			)
			(layer "F.SilkS")
		)
		(fp_line
			(start 0.67945 0.3048)
			(end 0.120396 0.3048)
			(stroke
				(width 0.1)
				(type default)
			)
			(layer "F.Fab")
		)
		(fp_line
			(start 0.67945 -0.3048)
			(end 0.67945 0.3048)
			(stroke
				(width 0.1)
				(type default)
			)
			(layer "F.Fab")
		)
		(fp_line
			(start 0.12065 -0.2794)
			(end 0.12065 -0.3048)
			(stroke
				(width 0.1)
				(type default)
			)
			(layer "F.Fab")
		)
		(fp_line
			(start 0.12065 -0.3048)
			(end 0.67945 -0.3048)
			(stroke
				(width 0.1)
				(type default)
			)
			(layer "F.Fab")
		)
		(fp_line
			(start 0.120396 0.3048)
			(end 0.120396 0.2794)
			(stroke
				(width 0.1)
				(type default)
			)
			(layer "F.Fab")
		)
		(fp_line
			(start 0.120396 0.2794)
			(end -0.12065 0.2794)
			(stroke
				(width 0.1)
				(type default)
			)
			(layer "F.Fab")
		)
		(fp_line
			(start -0.12065 0.3048)
			(end -0.67945 0.3048)
			(stroke
				(width 0.1)
				(type default)
			)
			(layer "F.Fab")
		)
		(fp_line
			(start -0.12065 0.2794)
			(end -0.12065 0.3048)
			(stroke
				(width 0.1)
				(type default)
			)
			(layer "F.Fab")
		)
		(fp_line
			(start -0.12065 -0.2794)
			(end 0.12065 -0.2794)
			(stroke
				(width 0.1)
				(type default)
			)
			(layer "F.Fab")
		)
		(fp_line
			(start -0.12065 -0.305054)
			(end -0.12065 -0.2794)
			(stroke
				(width 0.1)
				(type default)
			)
			(layer "F.Fab")
		)
		(fp_line
			(start -0.67945 0.3048)
			(end -0.67945 -0.305054)
			(stroke
				(width 0.1)
				(type default)
			)
			(layer "F.Fab")
		)
		(fp_line
			(start -0.67945 -0.305054)
			(end -0.12065 -0.305054)
			(stroke
				(width 0.1)
				(type default)
			)
			(layer "F.Fab")
		)
		(pad "1" smd circle
			(at -0.40005 0 180)
			(size 0 0)
			(layers "F.Cu" "F.Mask" "F.Paste")
			(net "NIC4_CLK")
		)
		(pad "2" smd circle
			(at 0.40005 0 180)
			(size 0 0)
			(layers "F.Cu" "F.Mask" "F.Paste")
			(net "GND")
		)
	)
	(footprint ""
		(layer "F.Cu")
		(at 262.353298 -291.390832)
		(property "Reference" "L124"
			(at 0 0 0)
			(layer "F.SilkS")
			(hide yes)
			(effects
				(font
					(size 1.27 1.27)
				)
			)
		)
		(property "Value" ""
			(at 0 0 0)
			(layer "F.Fab")
			(effects
				(font
					(size 1.27 1.27)
				)
			)
		)
		(duplicate_pad_numbers_are_jumpers no)
		(fp_line
			(start -1.63576 -0.8128)
			(end -1.63576 0.8128)
			(stroke
				(width 0.1524)
				(type default)
			)
			(layer "F.SilkS")
		)
		(fp_line
			(start -1.63576 -0.8128)
			(end 1.63576 -0.8128)
			(stroke
				(width 0.1524)
				(type default)
			)
			(layer "F.SilkS")
		)
		(fp_line
			(start 1.63576 -0.8128)
			(end 1.63576 0.8128)
			(stroke
				(width 0.1524)
				(type default)
			)
			(layer "F.SilkS")
		)
		(fp_line
			(start 1.63576 0.8128)
			(end -1.63576 0.8128)
			(stroke
				(width 0.1524)
				(type default)
			)
			(layer "F.SilkS")
		)
		(fp_line
			(start -1.56083 -0.738632)
			(end -1.56083 0.7366)
			(stroke
				(width 0.1)
				(type default)
			)
			(layer "F.Fab")
		)
		(fp_line
			(start -1.56083 0.7366)
			(end -1.524 0.7366)
			(stroke
				(width 0.1)
				(type default)
			)
			(layer "F.Fab")
		)
		(fp_line
			(start -1.524 0.7366)
			(end 1.524 0.7366)
			(stroke
				(width 0.1)
				(type default)
			)
			(layer "F.Fab")
		)
		(fp_line
			(start 1.524 0.7366)
			(end 1.560576 0.7366)
			(stroke
				(width 0.1)
				(type default)
			)
			(layer "F.Fab")
		)
		(fp_line
			(start 1.560576 -0.738632)
			(end -1.56083 -0.738632)
			(stroke
				(width 0.1)
				(type default)
			)
			(layer "F.Fab")
		)
		(fp_line
			(start 1.560576 0.7366)
			(end 1.560576 -0.738632)
			(stroke
				(width 0.1)
				(type default)
			)
			(layer "F.Fab")
		)
		(pad "1" smd rect
			(at -0.94996 0 180)
			(size 1.1176 1.3716)
			(layers "F.Cu" "F.Mask" "F.Paste")
			(net "P1V8_PLL0_PEX2")
		)
		(pad "2" smd rect
			(at 0.94996 0 180)
			(size 1.1176 1.3716)
			(layers "F.Cu" "F.Mask" "F.Paste")
			(net "PCEPLL4_VDDA18_PEX2")
		)
	)
	(footprint ""
		(layer "F.Cu")
		(at 374.543828 -49.95291 180)
		(property "Reference" "R643"
			(at 0 0 180)
			(layer "F.SilkS")
			(hide yes)
			(effects
				(font
					(size 1.27 1.27)
				)
			)
		)
		(property "Value" ""
			(at 0 0 180)
			(layer "F.Fab")
			(effects
				(font
					(size 1.27 1.27)
				)
			)
		)
		(duplicate_pad_numbers_are_jumpers no)
		(fp_line
			(start 0.7874 0.4064)
			(end -0.7874 0.4064)
			(stroke
				(width 0.1524)
				(type default)
			)
			(layer "F.SilkS")
		)
		(fp_line
			(start 0.7874 -0.4064)
			(end 0.7874 0.4064)
			(stroke
				(width 0.1524)
				(type default)
			)
			(layer "F.SilkS")
		)
		(fp_line
			(start -0.7874 0.4064)
			(end -0.7874 -0.4064)
			(stroke
				(width 0.1524)
				(type default)
			)
			(layer "F.SilkS")
		)
		(fp_line
			(start -0.7874 -0.4064)
			(end 0.7874 -0.4064)
			(stroke
				(width 0.1524)
				(type default)
			)
			(layer "F.SilkS")
		)
		(fp_line
			(start 0.67945 0.3048)
			(end 0.120396 0.3048)
			(stroke
				(width 0.1)
				(type default)
			)
			(layer "F.Fab")
		)
		(fp_line
			(start 0.67945 -0.3048)
			(end 0.67945 0.3048)
			(stroke
				(width 0.1)
				(type default)
			)
			(layer "F.Fab")
		)
		(fp_line
			(start 0.12065 -0.2794)
			(end 0.12065 -0.3048)
			(stroke
				(width 0.1)
				(type default)
			)
			(layer "F.Fab")
		)
		(fp_line
			(start 0.12065 -0.3048)
			(end 0.67945 -0.3048)
			(stroke
				(width 0.1)
				(type default)
			)
			(layer "F.Fab")
		)
		(fp_line
			(start 0.120396 0.3048)
			(end 0.120396 0.2794)
			(stroke
				(width 0.1)
				(type default)
			)
			(layer "F.Fab")
		)
		(fp_line
			(start 0.120396 0.2794)
			(end -0.12065 0.2794)
			(stroke
				(width 0.1)
				(type default)
			)
			(layer "F.Fab")
		)
		(fp_line
			(start -0.12065 0.3048)
			(end -0.67945 0.3048)
			(stroke
				(width 0.1)
				(type default)
			)
			(layer "F.Fab")
		)
		(fp_line
			(start -0.12065 0.2794)
			(end -0.12065 0.3048)
			(stroke
				(width 0.1)
				(type default)
			)
			(layer "F.Fab")
		)
		(fp_line
			(start -0.12065 -0.2794)
			(end 0.12065 -0.2794)
			(stroke
				(width 0.1)
				(type default)
			)
			(layer "F.Fab")
		)
		(fp_line
			(start -0.12065 -0.305054)
			(end -0.12065 -0.2794)
			(stroke
				(width 0.1)
				(type default)
			)
			(layer "F.Fab")
		)
		(fp_line
			(start -0.67945 0.3048)
			(end -0.67945 -0.305054)
			(stroke
				(width 0.1)
				(type default)
			)
			(layer "F.Fab")
		)
		(fp_line
			(start -0.67945 -0.305054)
			(end -0.12065 -0.305054)
			(stroke
				(width 0.1)
				(type default)
			)
			(layer "F.Fab")
		)
		(pad "1" smd circle
			(at -0.40005 0 180)
			(size 0 0)
			(layers "F.Cu" "F.Mask" "F.Paste")
			(net "SMB_BIC_I2C6_MUX_SSD_8_15_ADC_R_SCL")
		)
		(pad "2" smd circle
			(at 0.40005 0 180)
			(size 0 0)
			(layers "F.Cu" "F.Mask" "F.Paste")
			(net "SMB_SSD12_ADC_SCL")
		)
	)
	(footprint ""
		(layer "F.Cu")
		(at 148.417534 -115.336574 90)
		(property "Reference" "R145"
			(at 0 0 90)
			(layer "F.SilkS")
			(hide yes)
			(effects
				(font
					(size 1.27 1.27)
				)
			)
		)
		(property "Value" ""
			(at 0 0 90)
			(layer "F.Fab")
			(effects
				(font
					(size 1.27 1.27)
				)
			)
		)
		(duplicate_pad_numbers_are_jumpers no)
		(fp_line
			(start 0.7874 -0.4064)
			(end 0.7874 0.4064)
			(stroke
				(width 0.1524)
				(type default)
			)
			(layer "F.SilkS")
		)
		(fp_line
			(start -0.7874 -0.4064)
			(end 0.7874 -0.4064)
			(stroke
				(width 0.1524)
				(type default)
			)
			(layer "F.SilkS")
		)
		(fp_line
			(start 0.7874 0.4064)
			(end -0.7874 0.4064)
			(stroke
				(width 0.1524)
				(type default)
			)
			(layer "F.SilkS")
		)
		(fp_line
			(start -0.7874 0.4064)
			(end -0.7874 -0.4064)
			(stroke
				(width 0.1524)
				(type default)
			)
			(layer "F.SilkS")
		)
		(fp_line
			(start -0.12065 -0.305054)
			(end -0.12065 -0.2794)
			(stroke
				(width 0.1)
				(type default)
			)
			(layer "F.Fab")
		)
		(fp_line
			(start -0.67945 -0.305054)
			(end -0.12065 -0.305054)
			(stroke
				(width 0.1)
				(type default)
			)
			(layer "F.Fab")
		)
		(fp_line
			(start 0.67945 -0.3048)
			(end 0.67945 0.3048)
			(stroke
				(width 0.1)
				(type default)
			)
			(layer "F.Fab")
		)
		(fp_line
			(start 0.12065 -0.3048)
			(end 0.67945 -0.3048)
			(stroke
				(width 0.1)
				(type default)
			)
			(layer "F.Fab")
		)
		(fp_line
			(start 0.12065 -0.2794)
			(end 0.12065 -0.3048)
			(stroke
				(width 0.1)
				(type default)
			)
			(layer "F.Fab")
		)
		(fp_line
			(start -0.12065 -0.2794)
			(end 0.12065 -0.2794)
			(stroke
				(width 0.1)
				(type default)
			)
			(layer "F.Fab")
		)
		(fp_line
			(start 0.120396 0.2794)
			(end -0.12065 0.2794)
			(stroke
				(width 0.1)
				(type default)
			)
			(layer "F.Fab")
		)
		(fp_line
			(start -0.12065 0.2794)
			(end -0.12065 0.3048)
			(stroke
				(width 0.1)
				(type default)
			)
			(layer "F.Fab")
		)
		(fp_line
			(start 0.67945 0.3048)
			(end 0.120396 0.3048)
			(stroke
				(width 0.1)
				(type default)
			)
			(layer "F.Fab")
		)
		(fp_line
			(start 0.120396 0.3048)
			(end 0.120396 0.2794)
			(stroke
				(width 0.1)
				(type default)
			)
			(layer "F.Fab")
		)
		(fp_line
			(start -0.12065 0.3048)
			(end -0.67945 0.3048)
			(stroke
				(width 0.1)
				(type default)
			)
			(layer "F.Fab")
		)
		(fp_line
			(start -0.67945 0.3048)
			(end -0.67945 -0.305054)
			(stroke
				(width 0.1)
				(type default)
			)
			(layer "F.Fab")
		)
		(pad "1" smd circle
			(at -0.40005 0 90)
			(size 0 0)
			(layers "F.Cu" "F.Mask" "F.Paste")
			(net "PRSNT_NIC2_R_N")
		)
		(pad "2" smd circle
			(at 0.40005 0 90)
			(size 0 0)
			(layers "F.Cu" "F.Mask" "F.Paste")
			(net "PRSNT_NIC2_N")
		)
	)
	(footprint ""
		(layer "F.Cu")
		(at 414.273492 -191.410082)
		(property "Reference" "Q236"
			(at -0.3683 -3.474466 0)
			(unlocked yes)
			(layer "F.SilkS")
			(effects
				(font
					(size 0.7874 0.5842)
					(thickness 0.1524)
				)
			)
		)
		(property "Value" ""
			(at 0 0 0)
			(layer "F.Fab")
			(effects
				(font
					(size 1.27 1.27)
				)
			)
		)
		(duplicate_pad_numbers_are_jumpers no)
		(fp_line
			(start -1.376172 -1.199896)
			(end -0.508 -1.199896)
			(stroke
				(width 0.1524)
				(type default)
			)
			(layer "F.SilkS")
		)
		(fp_line
			(start -1.376172 1.199896)
			(end -1.376172 -1.199896)
			(stroke
				(width 0.1524)
				(type default)
			)
			(layer "F.SilkS")
		)
		(fp_line
			(start -0.508 -1.199896)
			(end 0 -0.762)
			(stroke
				(width 0.1524)
				(type default)
			)
			(layer "F.SilkS")
		)
		(fp_line
			(start 0 -0.762)
			(end 0.508 -1.199896)
			(stroke
				(width 0.1524)
				(type default)
			)
			(layer "F.SilkS")
		)
		(fp_line
			(start 0.508 -1.199896)
			(end 1.376172 -1.199896)
			(stroke
				(width 0.1524)
				(type default)
			)
			(layer "F.SilkS")
		)
		(fp_line
			(start 1.376172 -1.199896)
			(end 1.376172 1.199896)
			(stroke
				(width 0.1524)
				(type default)
			)
			(layer "F.SilkS")
		)
		(fp_line
			(start 1.376172 1.199896)
			(end -1.376172 1.199896)
			(stroke
				(width 0.1524)
				(type default)
			)
			(layer "F.SilkS")
		)
		(fp_poly
			(pts
				(xy -1.4605 -0.7493) (xy -2.2225 -1.1303) (xy -2.2225 -0.3683)
			)
			(stroke
				(width 0)
				(type default)
			)
			(fill yes)
			(layer "F.SilkS")
		)
		(fp_line
			(start -0.674878 -1.100074)
			(end 0.674878 -1.100074)
			(stroke
				(width 0.1)
				(type default)
			)
			(layer "F.Fab")
		)
		(fp_line
			(start -0.674878 1.100074)
			(end -0.674878 -1.100074)
			(stroke
				(width 0.1)
				(type default)
			)
			(layer "F.Fab")
		)
		(fp_line
			(start 0.674878 -1.100074)
			(end 0.674878 1.100074)
			(stroke
				(width 0.1)
				(type default)
			)
			(layer "F.Fab")
		)
		(fp_line
			(start 0.674878 1.100074)
			(end -0.674878 1.100074)
			(stroke
				(width 0.1)
				(type default)
			)
			(layer "F.Fab")
		)
		(fp_poly
			(pts
				(xy -1.4605 -0.7493) (xy -2.2225 -1.1303) (xy -2.2225 -0.3683)
			)
			(stroke
				(width 0)
				(type default)
			)
			(fill yes)
			(layer "F.Fab")
		)
		(pad "1" smd rect
			(at -0.899922 -0.750062 270)
			(size 0.6096 0.6096)
			(layers "F.Cu" "F.Mask" "F.Paste")
			(net "GND")
		)
		(pad "2" smd rect
			(at -0.899922 0 270)
			(size 0.4064 0.6096)
			(layers "F.Cu" "F.Mask" "F.Paste")
			(net "FPGA_PEX2_MODE_SEL1_R")
		)
		(pad "3" smd rect
			(at -0.899922 0.750062 270)
			(size 0.6096 0.6096)
			(layers "F.Cu" "F.Mask" "F.Paste")
			(net "FPGA_PEX2_MODE_SEL1_ISO")
		)
		(pad "4" smd rect
			(at 0.899922 0.750062 270)
			(size 0.6096 0.6096)
			(layers "F.Cu" "F.Mask" "F.Paste")
			(net "GND")
		)
		(pad "5" smd rect
			(at 0.899922 0 270)
			(size 0.4064 0.6096)
			(layers "F.Cu" "F.Mask" "F.Paste")
			(net "FPGA_PEX2_MODE_SEL1_D_N")
		)
		(pad "6" smd rect
			(at 0.899922 -0.750062 270)
			(size 0.6096 0.6096)
			(layers "F.Cu" "F.Mask" "F.Paste")
			(net "FPGA_PEX2_MODE_SEL1_D_N")
		)
	)
)
